# TIMECARD (Time Appliance Project (Time Card)) — schematic netlist excerpt (pin names and nets, part order shuffled) for the footprints in the layout excerpt that follows; sources: Cadence DE-HDL packaged netlist, KiCad conversion of R4006-B0001-02_R01.brd

C215  CAPACITOR  0.1UF 10V 10%  pkg SMC_0402R_H022  page 14 : \1\ = XP3R3V_FPGA ; \2\ = SG
R48  RESISTOR  5.1KOHM 1%  pkg SMC_0402R_H016  page 32 : \1\ = R_XP5R0V_EN ; \2\ = SG

(kicad_pcb
	(version 20260206)
	(generator "pcbnew")
	(generator_version "10.0")
	(general
		(thickness 1.6)
		(legacy_teardrops no)
	)
	(paper "A4")
	(title_block
		(title "timecard-production-celestica-r4006 — R4006-B0001-02_R01.brd")
		(comment 1 "Time Appliance Project (Time Card) / footprints 1007-1008 of 1113")
	)
	(layers
		(0 "F.Cu" signal "TOP")
		(4 "In1.Cu" signal "L02_GND1")
		(6 "In2.Cu" signal "L03_SIG1")
		(8 "In3.Cu" signal "L04_GND2")
		(10 "In4.Cu" signal "L05_VCC1")
		(12 "In5.Cu" signal "L06_VCC2")
		(14 "In6.Cu" signal "L07_GND3")
		(16 "In7.Cu" signal "L08_SIG2")
		(18 "In8.Cu" signal "L09_GND4")
		(2 "B.Cu" signal "BOTTOM")
		(9 "F.Adhes" user "F.Adhesive")
		(11 "B.Adhes" user "B.Adhesive")
		(13 "F.Paste" user "Package Geometry/Pastemask Top")
		(15 "B.Paste" user "Package Geometry/Pastemask Bottom")
		(5 "F.SilkS" user "Ref Des/Silkscreen Top")
		(7 "B.SilkS" user "Ref Des/Silkscreen Bottom")
		(1 "F.Mask" user "Board Geometry/Soldermask Top")
		(3 "B.Mask" user "Board Geometry/Soldermask Bottom")
		(17 "Dwgs.User" user "User.Drawings")
		(19 "Cmts.User" user "User.Comments")
		(21 "Eco1.User" user "User.Eco1")
		(23 "Eco2.User" user "User.Eco2")
		(25 "Edge.Cuts" user "Board Geometry/Outline")
		(27 "Margin" user)
		(31 "F.CrtYd" user "Package Geometry/Place Bound Top")
		(29 "B.CrtYd" user "Package Geometry/Place Bound Bottom")
		(35 "F.Fab" user "Ref Des/Assembly Top")
		(33 "B.Fab" user "Ref Des/Assembly Bottom")
	)
	(footprint ""
		(layer "B.Cu")
		(at 117.347238 -48.823118 180)
		(property "Reference" "C215"
			(at 0.634238 1.945132 0)
			(unlocked yes)
			(layer "B.SilkS")
			(effects
				(font
					(size 0.635 0.4064)
					(thickness 0.1524)
				)
				(justify mirror)
			)
		)
		(property "Value" "VAL*"
			(at 0 3.718306 180)
			(unlocked yes)
			(layer "B.Fab")
			(hide yes)
			(effects
				(font
					(size 0.7874 0.5842)
					(thickness 0.127)
				)
				(justify mirror)
			)
		)
		(property "Tolerance" "TOL*"
			(at 0 4.861306 180)
			(unlocked yes)
			(layer "Cmts.User")
			(hide yes)
			(effects
				(font
					(size 0.7874 0.5842)
					(thickness 0.127)
				)
				(justify mirror)
			)
		)
		(property "User Part Number" "PARTNUM*"
			(at 0 2.575306 180)
			(unlocked yes)
			(layer "Cmts.User")
			(hide yes)
			(effects
				(font
					(size 0.7874 0.5842)
					(thickness 0.127)
				)
				(justify mirror)
			)
		)
		(property "Device Type" "CAPACITOR-G105-0B104-CK,0.1UF,A"
			(at 0 1.432306 180)
			(unlocked yes)
			(layer "B.Fab")
			(hide yes)
			(effects
				(font
					(size 0.7874 0.5842)
					(thickness 0.127)
				)
				(justify mirror)
			)
		)
		(duplicate_pad_numbers_are_jumpers no)
		(fp_line
			(start 0.970026 0.4699)
			(end 0.970026 -0.4699)
			(stroke
				(width 0.1)
				(type default)
			)
			(layer "B.SilkS")
		)
		(fp_line
			(start 0.970026 -0.4699)
			(end -0.970026 -0.4699)
			(stroke
				(width 0.1)
				(type default)
			)
			(layer "B.SilkS")
		)
		(fp_line
			(start -0.970026 0.4699)
			(end 0.970026 0.4699)
			(stroke
				(width 0.1)
				(type default)
			)
			(layer "B.SilkS")
		)
		(fp_line
			(start -0.970026 -0.4699)
			(end -0.970026 0.4699)
			(stroke
				(width 0.1)
				(type default)
			)
			(layer "B.SilkS")
		)
		(fp_poly
			(pts
				(xy 0.970026 0.4699) (xy -0.970026 0.4699) (xy -0.970026 -0.4699) (xy 0.970026 -0.4699)
			)
			(stroke
				(width 0)
				(type default)
			)
			(fill no)
			(layer "B.CrtYd")
		)
		(fp_line
			(start 0.508 0.3048)
			(end 0.508 -0.3048)
			(stroke
				(width 0.1)
				(type default)
			)
			(layer "B.Fab")
		)
		(fp_line
			(start 0.508 -0.3048)
			(end -0.508 -0.3048)
			(stroke
				(width 0.1)
				(type default)
			)
			(layer "B.Fab")
		)
		(fp_line
			(start -0.508 0.3048)
			(end 0.508 0.3048)
			(stroke
				(width 0.1)
				(type default)
			)
			(layer "B.Fab")
		)
		(fp_line
			(start -0.508 -0.3048)
			(end -0.508 0.3048)
			(stroke
				(width 0.1)
				(type default)
			)
			(layer "B.Fab")
		)
		(pad "1" smd circle
			(at 0.500126 0)
			(size 0.635 0.635)
			(layers "B.Cu" "B.Mask" "B.Paste")
			(net "XP3R3V_FPGA")
		)
		(pad "2" smd circle
			(at -0.500126 0)
			(size 0.635 0.635)
			(layers "B.Cu" "B.Mask" "B.Paste")
			(net "SG")
		)
	)
	(footprint ""
		(layer "B.Cu")
		(at 36.9824 -100.2284)
		(property "Reference" "R48"
			(at -4.0386 0.64897 0)
			(unlocked yes)
			(layer "B.SilkS")
			(effects
				(font
					(size 0.7874 0.5842)
					(thickness 0.1524)
				)
				(justify mirror)
			)
		)
		(property "Value" "VAL*"
			(at -0.02032 2.13233 0)
			(unlocked yes)
			(layer "B.Fab")
			(hide yes)
			(effects
				(font
					(size 0.7874 0.5842)
					(thickness 0.1524)
				)
				(justify mirror)
			)
		)
		(property "Device Type" "RESISTOR-A155-05101-DL,5.1KOHMA"
			(at -0.008382 1.210564 0)
			(unlocked yes)
			(layer "B.Fab")
			(hide yes)
			(effects
				(font
					(size 0.7874 0.5842)
					(thickness 0.1524)
				)
				(justify mirror)
			)
		)
		(property "User Part Number" "PARTNUM*"
			(at -0.02032 4.024884 0)
			(unlocked yes)
			(layer "Cmts.User")
			(hide yes)
			(effects
				(font
					(size 0.7874 0.5842)
					(thickness 0.1524)
				)
				(justify mirror)
			)
		)
		(property "Tolerance" "TOL*"
			(at -0.044704 3.05435 0)
			(unlocked yes)
			(layer "Cmts.User")
			(hide yes)
			(effects
				(font
					(size 0.7874 0.5842)
					(thickness 0.1524)
				)
				(justify mirror)
			)
		)
		(duplicate_pad_numbers_are_jumpers no)
		(fp_line
			(start -1.143 -0.5588)
			(end 1.143 -0.5588)
			(stroke
				(width 0.1)
				(type default)
			)
			(layer "B.SilkS")
		)
		(fp_line
			(start -1.143 0.5588)
			(end -1.143 -0.5588)
			(stroke
				(width 0.1)
				(type default)
			)
			(layer "B.SilkS")
		)
		(fp_line
			(start 1.143 -0.5588)
			(end 1.143 0.5588)
			(stroke
				(width 0.1)
				(type default)
			)
			(layer "B.SilkS")
		)
		(fp_line
			(start 1.143 0.5588)
			(end -1.143 0.5588)
			(stroke
				(width 0.1)
				(type default)
			)
			(layer "B.SilkS")
		)
		(fp_rect
			(start 1.143 -0.5588)
			(end -1.143 0.5588)
			(stroke
				(width 0)
				(type default)
			)
			(fill no)
			(layer "B.CrtYd")
		)
		(fp_line
			(start -0.508 -0.3048)
			(end 0.508 -0.3048)
			(stroke
				(width 0.1)
				(type default)
			)
			(layer "B.Fab")
		)
		(fp_line
			(start -0.508 0.3048)
			(end -0.508 -0.3048)
			(stroke
				(width 0.1)
				(type default)
			)
			(layer "B.Fab")
		)
		(fp_line
			(start 0.508 -0.3048)
			(end 0.508 0.3048)
			(stroke
				(width 0.1)
				(type default)
			)
			(layer "B.Fab")
		)
		(fp_line
			(start 0.508 0.3048)
			(end -0.508 0.3048)
			(stroke
				(width 0.1)
				(type default)
			)
			(layer "B.Fab")
		)
		(pad "1" smd rect
			(at 0.5334 0 180)
			(size 0.7112 0.6096)
			(layers "B.Cu" "B.Mask" "B.Paste")
			(net "R_XP5R0V_EN")
		)
		(pad "2" smd rect
			(at -0.5334 0 180)
			(size 0.7112 0.6096)
			(layers "B.Cu" "B.Mask" "B.Paste")
			(net "SG")
		)
		(zone
			(layer "B.Cu")
			(hatch none 0.5)
			(connect_pads
				(clearance 0)
			)
			(min_thickness 0.25)
			(keepout
				(tracks allowed)
				(vias not_allowed)
				(pads allowed)
				(copperpour not_allowed)
				(footprints allowed)
			)
			(placement
				(enabled no)
				(sheetname "")
			)
			(fill
				(thermal_gap 0.5)
				(thermal_bridge_width 0.5)
				(island_removal_mode 0)
			)
			(polygon
				(pts
					(xy 37.0586 -100.5332) (xy 36.9062 -100.5332) (xy 36.9062 -99.9236) (xy 37.0586 -99.9236)
				)
			)
		)
	)
)
